FILE_TYPE = MULTI_PHYS_TABLE;
PART 'PCA9617'
{===============================================================================================================================================================================================================}
:PACK_TYPE | MATERIAL | PART_NUMBER     = EnvComp | PART_NUMBER  | JEDEC_TYPE        | DESCRIPTION                     | CLASS | COMPONENT_TYPE | HEIGHT     | LPID   | SPEED_URL | Status |RPL| AML | Bus_Unit | Days ;
{===============================================================================================================================================================================================================}
'SSOP'     | 'IC'     | 'G81764-001'(!) = 'YES;YES;YES;UNK;ok;VLD' | 'G81764-001' | 'SSOP8_12_65MC'   |'IC,BUF/DVR,I2C,SSOP,PCA9617ADP' | 'IC'  | 'SUB50'        | '0.043 IN' |'2481'  | 'http://speed.intel.com:8081/speed/module/pdm/item/pdm_item_detail_direct.asp?item_cde=G81764-001&item_rev=01&url_param=unused' | 'Design' | 'NO' | '1' | 'SMO_IC' | '???' 
'SSOP'     | 'EMPTY'  | 'G81764-001'(!) = 'YES;YES;YES;UNK;ok;VLD' | 'G81764-001' | 'SSOP8_12_65MC'   |'IC,BUF/DVR,I2C,SSOP,PCA9617ADP' | 'IO'  | 'SUB50'        | '0.043 IN' |'2481'  | 'http://speed.intel.com:8081/speed/module/pdm/item/pdm_item_detail_direct.asp?item_cde=G81764-001&item_rev=01&url_param=unused' | 'Design' | 'NO' | '1' | 'SMO_IC' | '???' 
END_PART
END.
